(kicad_pcb
	(version 20260206)
	(generator "pcbnew")
	(generator_version "10.0")
	(general
		(thickness 1.6)
		(legacy_teardrops no)
	)
	(paper "A4")
	(title_block
		(title "04192023_DAF0TMB3IC0_F0TG_MB_C_brd_V02_OCP.brd")
		(comment 1 "Grand Teton / footprints 1294-1300 of 8354")
	)
	(layers
		(0 "F.Cu" signal "TOP")
		(4 "In1.Cu" signal "GND")
		(6 "In2.Cu" signal "IN1")
		(8 "In3.Cu" signal "GND1")
		(10 "In4.Cu" signal "IN2")
		(12 "In5.Cu" signal "GND2")
		(14 "In6.Cu" signal "IN3")
		(16 "In7.Cu" signal "GND3")
		(18 "In8.Cu" signal "VCC")
		(20 "In9.Cu" signal "VCC1")
		(22 "In10.Cu" signal "GND4")
		(24 "In11.Cu" signal "IN4")
		(26 "In12.Cu" signal "GND5")
		(28 "In13.Cu" signal "IN5")
		(30 "In14.Cu" signal "GND6")
		(32 "In15.Cu" signal "IN6")
		(34 "In16.Cu" signal "GND7")
		(2 "B.Cu" signal "BOTTOM")
		(9 "F.Adhes" user "F.Adhesive")
		(11 "B.Adhes" user "B.Adhesive")
		(13 "F.Paste" user "Package Geometry/Pastemask Top")
		(15 "B.Paste" user "Package Geometry/Pastemask Bottom")
		(5 "F.SilkS" user "Ref Des/Silkscreen Top")
		(7 "B.SilkS" user "Ref Des/Silkscreen Bottom")
		(1 "F.Mask" user "Board Geometry/Soldermask Top")
		(3 "B.Mask" user "Board Geometry/Soldermask Bottom")
		(17 "Dwgs.User" user "User.Drawings")
		(19 "Cmts.User" user "User.Comments")
		(21 "Eco1.User" user "User.Eco1")
		(23 "Eco2.User" user "User.Eco2")
		(25 "Edge.Cuts" user "Board Geometry/Outline")
		(27 "Margin" user)
		(31 "F.CrtYd" user "Package Geometry/Place Bound Top")
		(29 "B.CrtYd" user "Package Geometry/Place Bound Bottom")
		(35 "F.Fab" user "Ref Des/Assembly Top")
		(33 "B.Fab" user "Ref Des/Assembly Bottom")
	)
	(footprint ""
		(layer "F.Cu")
		(at 108.533946 -54.882034 -90)
		(property "Reference" "R6312"
			(at 0 0 270)
			(layer "F.SilkS")
			(hide yes)
			(effects
				(font
					(size 1.27 1.27)
				)
			)
		)
		(property "Value" ""
			(at 0 0 270)
			(layer "F.Fab")
			(effects
				(font
					(size 1.27 1.27)
				)
			)
		)
		(duplicate_pad_numbers_are_jumpers no)
		(fp_line
			(start -0.7874 0.4064)
			(end -0.7874 -0.4064)
			(stroke
				(width 0.1524)
				(type default)
			)
			(layer "F.SilkS")
		)
		(fp_line
			(start 0.7874 0.4064)
			(end -0.7874 0.4064)
			(stroke
				(width 0.1524)
				(type default)
			)
			(layer "F.SilkS")
		)
		(fp_line
			(start -0.7874 -0.4064)
			(end 0.7874 -0.4064)
			(stroke
				(width 0.1524)
				(type default)
			)
			(layer "F.SilkS")
		)
		(fp_line
			(start 0.7874 -0.4064)
			(end 0.7874 0.4064)
			(stroke
				(width 0.1524)
				(type default)
			)
			(layer "F.SilkS")
		)
		(fp_line
			(start -0.67945 0.3048)
			(end -0.67945 -0.305054)
			(stroke
				(width 0.1)
				(type default)
			)
			(layer "F.Fab")
		)
		(fp_line
			(start -0.12065 0.3048)
			(end -0.67945 0.3048)
			(stroke
				(width 0.1)
				(type default)
			)
			(layer "F.Fab")
		)
		(fp_line
			(start 0.120396 0.3048)
			(end 0.120396 0.2794)
			(stroke
				(width 0.1)
				(type default)
			)
			(layer "F.Fab")
		)
		(fp_line
			(start 0.67945 0.3048)
			(end 0.120396 0.3048)
			(stroke
				(width 0.1)
				(type default)
			)
			(layer "F.Fab")
		)
		(fp_line
			(start -0.12065 0.2794)
			(end -0.12065 0.3048)
			(stroke
				(width 0.1)
				(type default)
			)
			(layer "F.Fab")
		)
		(fp_line
			(start 0.120396 0.2794)
			(end -0.12065 0.2794)
			(stroke
				(width 0.1)
				(type default)
			)
			(layer "F.Fab")
		)
		(fp_line
			(start -0.12065 -0.2794)
			(end 0.12065 -0.2794)
			(stroke
				(width 0.1)
				(type default)
			)
			(layer "F.Fab")
		)
		(fp_line
			(start 0.12065 -0.2794)
			(end 0.12065 -0.3048)
			(stroke
				(width 0.1)
				(type default)
			)
			(layer "F.Fab")
		)
		(fp_line
			(start 0.12065 -0.3048)
			(end 0.67945 -0.3048)
			(stroke
				(width 0.1)
				(type default)
			)
			(layer "F.Fab")
		)
		(fp_line
			(start 0.67945 -0.3048)
			(end 0.67945 0.3048)
			(stroke
				(width 0.1)
				(type default)
			)
			(layer "F.Fab")
		)
		(fp_line
			(start -0.67945 -0.305054)
			(end -0.12065 -0.305054)
			(stroke
				(width 0.1)
				(type default)
			)
			(layer "F.Fab")
		)
		(fp_line
			(start -0.12065 -0.305054)
			(end -0.12065 -0.2794)
			(stroke
				(width 0.1)
				(type default)
			)
			(layer "F.Fab")
		)
		(pad "1" smd circle
			(at -0.40005 0 270)
			(size 0 0)
			(layers "F.Cu" "F.Mask" "F.Paste")
			(net "P3V3_AUX")
		)
		(pad "2" smd circle
			(at 0.40005 0 270)
			(size 0 0)
			(layers "F.Cu" "F.Mask" "F.Paste")
			(net "USB_HUB2_TI_OVERCUR1")
		)
	)
	(footprint ""
		(layer "F.Cu")
		(at 217.881962 -68.340478)
		(property "Reference" "PR3963"
			(at 0 0 0)
			(layer "F.SilkS")
			(hide yes)
			(effects
				(font
					(size 1.27 1.27)
				)
			)
		)
		(property "Value" ""
			(at 0 0 0)
			(layer "F.Fab")
			(effects
				(font
					(size 1.27 1.27)
				)
			)
		)
		(duplicate_pad_numbers_are_jumpers no)
		(fp_line
			(start -0.7874 -0.4064)
			(end 0.7874 -0.4064)
			(stroke
				(width 0.1524)
				(type default)
			)
			(layer "F.SilkS")
		)
		(fp_line
			(start -0.7874 0.4064)
			(end -0.7874 -0.4064)
			(stroke
				(width 0.1524)
				(type default)
			)
			(layer "F.SilkS")
		)
		(fp_line
			(start 0.7874 -0.4064)
			(end 0.7874 0.4064)
			(stroke
				(width 0.1524)
				(type default)
			)
			(layer "F.SilkS")
		)
		(fp_line
			(start 0.7874 0.4064)
			(end -0.7874 0.4064)
			(stroke
				(width 0.1524)
				(type default)
			)
			(layer "F.SilkS")
		)
		(fp_line
			(start -0.67945 -0.305054)
			(end -0.12065 -0.305054)
			(stroke
				(width 0.1)
				(type default)
			)
			(layer "F.Fab")
		)
		(fp_line
			(start -0.67945 0.3048)
			(end -0.67945 -0.305054)
			(stroke
				(width 0.1)
				(type default)
			)
			(layer "F.Fab")
		)
		(fp_line
			(start -0.12065 -0.305054)
			(end -0.12065 -0.2794)
			(stroke
				(width 0.1)
				(type default)
			)
			(layer "F.Fab")
		)
		(fp_line
			(start -0.12065 -0.2794)
			(end 0.12065 -0.2794)
			(stroke
				(width 0.1)
				(type default)
			)
			(layer "F.Fab")
		)
		(fp_line
			(start -0.12065 0.2794)
			(end -0.12065 0.3048)
			(stroke
				(width 0.1)
				(type default)
			)
			(layer "F.Fab")
		)
		(fp_line
			(start -0.12065 0.3048)
			(end -0.67945 0.3048)
			(stroke
				(width 0.1)
				(type default)
			)
			(layer "F.Fab")
		)
		(fp_line
			(start 0.120396 0.2794)
			(end -0.12065 0.2794)
			(stroke
				(width 0.1)
				(type default)
			)
			(layer "F.Fab")
		)
		(fp_line
			(start 0.120396 0.3048)
			(end 0.120396 0.2794)
			(stroke
				(width 0.1)
				(type default)
			)
			(layer "F.Fab")
		)
		(fp_line
			(start 0.12065 -0.3048)
			(end 0.67945 -0.3048)
			(stroke
				(width 0.1)
				(type default)
			)
			(layer "F.Fab")
		)
		(fp_line
			(start 0.12065 -0.2794)
			(end 0.12065 -0.3048)
			(stroke
				(width 0.1)
				(type default)
			)
			(layer "F.Fab")
		)
		(fp_line
			(start 0.67945 -0.3048)
			(end 0.67945 0.3048)
			(stroke
				(width 0.1)
				(type default)
			)
			(layer "F.Fab")
		)
		(fp_line
			(start 0.67945 0.3048)
			(end 0.120396 0.3048)
			(stroke
				(width 0.1)
				(type default)
			)
			(layer "F.Fab")
		)
		(pad "1" smd circle
			(at -0.40005 0)
			(size 0 0)
			(layers "F.Cu" "F.Mask" "F.Paste")
			(net "P3V3_AUX")
		)
		(pad "2" smd circle
			(at 0.40005 0)
			(size 0 0)
			(layers "F.Cu" "F.Mask" "F.Paste")
			(net "P3V3_E1S_UV_0")
		)
	)
	(footprint ""
		(layer "F.Cu")
		(at 90.833702 -370.57203 -90)
		(property "Reference" "C723"
			(at 0 0 270)
			(layer "F.SilkS")
			(hide yes)
			(effects
				(font
					(size 1.27 1.27)
				)
			)
		)
		(property "Value" ""
			(at 0 0 270)
			(layer "F.Fab")
			(effects
				(font
					(size 1.27 1.27)
				)
			)
		)
		(duplicate_pad_numbers_are_jumpers no)
		(fp_line
			(start -0.299974 0.150114)
			(end -0.299974 -0.150114)
			(stroke
				(width 0.1)
				(type default)
			)
			(layer "F.Fab")
		)
		(fp_line
			(start 0.299974 0.150114)
			(end -0.299974 0.150114)
			(stroke
				(width 0.1)
				(type default)
			)
			(layer "F.Fab")
		)
		(fp_line
			(start -0.299974 -0.150114)
			(end 0.299974 -0.150114)
			(stroke
				(width 0.1)
				(type default)
			)
			(layer "F.Fab")
		)
		(fp_line
			(start 0.299974 -0.150114)
			(end 0.299974 0.150114)
			(stroke
				(width 0.1)
				(type default)
			)
			(layer "F.Fab")
		)
		(pad "1" smd rect
			(at -0.2667 0 270)
			(size 0.3048 0.381)
			(layers "F.Cu" "F.Mask" "F.Paste")
			(net "P5E_CPU1_P1_TX_C_DP<9>")
		)
		(pad "2" smd rect
			(at 0.2667 0 270)
			(size 0.3048 0.381)
			(layers "F.Cu" "F.Mask" "F.Paste")
			(net "P5E_CPU1_P1_TX_DP<9>")
		)
	)
	(footprint ""
		(layer "F.Cu")
		(at 365.387128 -324.29704 90)
		(property "Reference" "R2660"
			(at 0 0 90)
			(layer "F.SilkS")
			(hide yes)
			(effects
				(font
					(size 1.27 1.27)
				)
			)
		)
		(property "Value" ""
			(at 0 0 90)
			(layer "F.Fab")
			(effects
				(font
					(size 1.27 1.27)
				)
			)
		)
		(duplicate_pad_numbers_are_jumpers no)
		(fp_line
			(start 0.7874 -0.4064)
			(end 0.7874 -0.008128)
			(stroke
				(width 0.1524)
				(type default)
			)
			(layer "F.SilkS")
		)
		(fp_line
			(start -0.7874 -0.4064)
			(end 0.7874 -0.4064)
			(stroke
				(width 0.1524)
				(type default)
			)
			(layer "F.SilkS")
		)
		(fp_line
			(start -0.7874 -0.008128)
			(end -0.7874 -0.4064)
			(stroke
				(width 0.1524)
				(type default)
			)
			(layer "F.SilkS")
		)
		(fp_line
			(start 0.39116 0.4064)
			(end -0.34544 0.4064)
			(stroke
				(width 0.1524)
				(type default)
			)
			(layer "F.SilkS")
		)
		(fp_line
			(start -0.12065 -0.305054)
			(end -0.12065 -0.2794)
			(stroke
				(width 0.1)
				(type default)
			)
			(layer "F.Fab")
		)
		(fp_line
			(start -0.67945 -0.305054)
			(end -0.12065 -0.305054)
			(stroke
				(width 0.1)
				(type default)
			)
			(layer "F.Fab")
		)
		(fp_line
			(start 0.67945 -0.3048)
			(end 0.67945 0.3048)
			(stroke
				(width 0.1)
				(type default)
			)
			(layer "F.Fab")
		)
		(fp_line
			(start 0.12065 -0.3048)
			(end 0.67945 -0.3048)
			(stroke
				(width 0.1)
				(type default)
			)
			(layer "F.Fab")
		)
		(fp_line
			(start 0.12065 -0.2794)
			(end 0.12065 -0.3048)
			(stroke
				(width 0.1)
				(type default)
			)
			(layer "F.Fab")
		)
		(fp_line
			(start -0.12065 -0.2794)
			(end 0.12065 -0.2794)
			(stroke
				(width 0.1)
				(type default)
			)
			(layer "F.Fab")
		)
		(fp_line
			(start 0.120396 0.2794)
			(end -0.12065 0.2794)
			(stroke
				(width 0.1)
				(type default)
			)
			(layer "F.Fab")
		)
		(fp_line
			(start -0.12065 0.2794)
			(end -0.12065 0.3048)
			(stroke
				(width 0.1)
				(type default)
			)
			(layer "F.Fab")
		)
		(fp_line
			(start 0.67945 0.3048)
			(end 0.120396 0.3048)
			(stroke
				(width 0.1)
				(type default)
			)
			(layer "F.Fab")
		)
		(fp_line
			(start 0.120396 0.3048)
			(end 0.120396 0.2794)
			(stroke
				(width 0.1)
				(type default)
			)
			(layer "F.Fab")
		)
		(fp_line
			(start -0.12065 0.3048)
			(end -0.67945 0.3048)
			(stroke
				(width 0.1)
				(type default)
			)
			(layer "F.Fab")
		)
		(fp_line
			(start -0.67945 0.3048)
			(end -0.67945 -0.305054)
			(stroke
				(width 0.1)
				(type default)
			)
			(layer "F.Fab")
		)
		(pad "1" smd circle
			(at -0.40005 0 90)
			(size 0 0)
			(layers "F.Cu" "F.Mask" "F.Paste")
			(net "CLK_100M_CPU0_CLK11_R_DN")
		)
		(pad "2" smd circle
			(at 0.40005 0 90)
			(size 0 0)
			(layers "F.Cu" "F.Mask" "F.Paste")
			(net "CLK_100M_CPU0_CLK11_DN")
		)
	)
	(footprint ""
		(layer "F.Cu")
		(at 342.7349 -16.178276 90)
		(property "Reference" "D6"
			(at -3.95732 -1.496568 90)
			(unlocked yes)
			(layer "F.SilkS")
			(effects
				(font
					(size 0.7874 0.5842)
					(thickness 0.1524)
				)
				(justify left)
			)
		)
		(property "Value" ""
			(at 0 0 90)
			(layer "F.Fab")
			(effects
				(font
					(size 1.27 1.27)
				)
			)
		)
		(duplicate_pad_numbers_are_jumpers no)
		(fp_line
			(start 1.778 -0.5588)
			(end 1.3208 -0.5588)
			(stroke
				(width 0.1524)
				(type default)
			)
			(layer "F.SilkS")
		)
		(fp_line
			(start 1.778 -0.5588)
			(end 1.778 0.5588)
			(stroke
				(width 0.1524)
				(type default)
			)
			(layer "F.SilkS")
		)
		(fp_line
			(start 1.4732 -0.5588)
			(end 1.4732 0.5588)
			(stroke
				(width 0.1524)
				(type default)
			)
			(layer "F.SilkS")
		)
		(fp_line
			(start 1.3208 -0.5588)
			(end 1.3208 0.5588)
			(stroke
				(width 0.1524)
				(type default)
			)
			(layer "F.SilkS")
		)
		(fp_line
			(start -1.3208 -0.5588)
			(end 1.3208 -0.5588)
			(stroke
				(width 0.1524)
				(type default)
			)
			(layer "F.SilkS")
		)
		(fp_line
			(start 1.778 0.5588)
			(end 1.3208 0.5588)
			(stroke
				(width 0.1524)
				(type default)
			)
			(layer "F.SilkS")
		)
		(fp_line
			(start 1.6256 0.5588)
			(end 1.6256 -0.5588)
			(stroke
				(width 0.1524)
				(type default)
			)
			(layer "F.SilkS")
		)
		(fp_line
			(start 1.3208 0.5588)
			(end -1.3208 0.5588)
			(stroke
				(width 0.1524)
				(type default)
			)
			(layer "F.SilkS")
		)
		(fp_line
			(start -1.3208 0.5588)
			(end -1.3208 -0.5588)
			(stroke
				(width 0.1524)
				(type default)
			)
			(layer "F.SilkS")
		)
		(fp_line
			(start 0.899922 -0.40005)
			(end 0.899922 0.40005)
			(stroke
				(width 0.1)
				(type default)
			)
			(layer "F.Fab")
		)
		(fp_line
			(start -0.899922 -0.40005)
			(end 0.899922 -0.40005)
			(stroke
				(width 0.1)
				(type default)
			)
			(layer "F.Fab")
		)
		(fp_line
			(start 0.899922 0.40005)
			(end -0.899922 0.40005)
			(stroke
				(width 0.1)
				(type default)
			)
			(layer "F.Fab")
		)
		(fp_line
			(start -0.899922 0.40005)
			(end -0.899922 -0.40005)
			(stroke
				(width 0.1)
				(type default)
			)
			(layer "F.Fab")
		)
		(fp_text user "+"
			(at -2.620518 -0.653796 90)
			(unlocked yes)
			(layer "F.SilkS")
			(effects
				(font
					(size 1.905 1.4224)
					(thickness 0.1524)
				)
				(justify left)
			)
		)
		(fp_text user "-"
			(at 1.651 -0.22225 90)
			(unlocked yes)
			(layer "F.SilkS")
			(effects
				(font
					(size 1.905 1.4224)
					(thickness 0.1524)
				)
				(justify left)
			)
		)
		(fp_text user "-"
			(at 1.651 -0.22225 90)
			(unlocked yes)
			(layer "F.Fab")
			(effects
				(font
					(size 1.905 1.4224)
					(thickness 0.1524)
				)
				(justify left)
			)
		)
		(fp_text user "+"
			(at -2.6162 -0.22225 90)
			(unlocked yes)
			(layer "F.Fab")
			(effects
				(font
					(size 1.905 1.4224)
					(thickness 0.1524)
				)
				(justify left)
			)
		)
		(pad "A" smd rect
			(at -0.750062 0 90)
			(size 0.8128 0.8128)
			(layers "F.Cu" "F.Mask" "F.Paste")
			(net "PU_SMERR_LED")
		)
		(pad "C" smd rect
			(at 0.750062 0 90)
			(size 0.8128 0.8128)
			(layers "F.Cu" "F.Mask" "F.Paste")
			(net "SMERR_LED_N")
		)
	)
	(footprint ""
		(layer "F.Cu")
		(at 311.816496 -383.88163 -90)
		(property "Reference" "C918"
			(at 0 0 270)
			(layer "F.SilkS")
			(hide yes)
			(effects
				(font
					(size 1.27 1.27)
				)
			)
		)
		(property "Value" ""
			(at 0 0 270)
			(layer "F.Fab")
			(effects
				(font
					(size 1.27 1.27)
				)
			)
		)
		(duplicate_pad_numbers_are_jumpers no)
		(fp_line
			(start -0.299974 0.150114)
			(end -0.299974 -0.150114)
			(stroke
				(width 0.1)
				(type default)
			)
			(layer "F.Fab")
		)
		(fp_line
			(start 0.299974 0.150114)
			(end -0.299974 0.150114)
			(stroke
				(width 0.1)
				(type default)
			)
			(layer "F.Fab")
		)
		(fp_line
			(start -0.299974 -0.150114)
			(end 0.299974 -0.150114)
			(stroke
				(width 0.1)
				(type default)
			)
			(layer "F.Fab")
		)
		(fp_line
			(start 0.299974 -0.150114)
			(end 0.299974 0.150114)
			(stroke
				(width 0.1)
				(type default)
			)
			(layer "F.Fab")
		)
		(pad "1" smd rect
			(at -0.2667 0 270)
			(size 0.3048 0.381)
			(layers "F.Cu" "F.Mask" "F.Paste")
			(net "P5E_CPU0_P0_TX_C_DN<7>")
		)
		(pad "2" smd rect
			(at 0.2667 0 270)
			(size 0.3048 0.381)
			(layers "F.Cu" "F.Mask" "F.Paste")
			(net "P5E_CPU0_P0_TX_DN<7>")
		)
	)
	(footprint ""
		(layer "F.Cu")
		(at 183.269636 -361.600242 180)
		(property "Reference" "PL56"
			(at 0.643636 2.863088 0)
			(unlocked yes)
			(layer "F.SilkS")
			(effects
				(font
					(size 0.7874 0.5842)
					(thickness 0.1524)
				)
				(justify left)
			)
		)
		(property "Value" ""
			(at 0 0 180)
			(layer "F.Fab")
			(effects
				(font
					(size 1.27 1.27)
				)
			)
		)
		(duplicate_pad_numbers_are_jumpers no)
		(fp_line
			(start 2.249932 2.249932)
			(end -2.249932 2.249932)
			(stroke
				(width 0.1524)
				(type default)
			)
			(layer "F.SilkS")
		)
		(fp_line
			(start 2.249932 1.3843)
			(end 2.249932 2.249932)
			(stroke
				(width 0.1524)
				(type default)
			)
			(layer "F.SilkS")
		)
		(fp_line
			(start 2.249932 -2.249932)
			(end 2.249932 -1.3843)
			(stroke
				(width 0.1524)
				(type default)
			)
			(layer "F.SilkS")
		)
		(fp_line
			(start -2.249932 2.249932)
			(end -2.249932 1.3843)
			(stroke
				(width 0.1524)
				(type default)
			)
			(layer "F.SilkS")
		)
		(fp_line
			(start -2.249932 -1.3843)
			(end -2.249932 -2.249932)
			(stroke
				(width 0.1524)
				(type default)
			)
			(layer "F.SilkS")
		)
		(fp_line
			(start -2.249932 -2.249932)
			(end 2.249932 -2.249932)
			(stroke
				(width 0.1524)
				(type default)
			)
			(layer "F.SilkS")
		)
		(fp_line
			(start 2.249932 2.249932)
			(end -2.249932 2.249932)
			(stroke
				(width 0.1)
				(type default)
			)
			(layer "F.Fab")
		)
		(fp_line
			(start 2.249932 -2.249932)
			(end 2.249932 2.249932)
			(stroke
				(width 0.1)
				(type default)
			)
			(layer "F.Fab")
		)
		(fp_line
			(start -2.249932 2.249932)
			(end -2.249932 -2.249932)
			(stroke
				(width 0.1)
				(type default)
			)
			(layer "F.Fab")
		)
		(fp_line
			(start -2.249932 -2.249932)
			(end 2.249932 -2.249932)
			(stroke
				(width 0.1)
				(type default)
			)
			(layer "F.Fab")
		)
		(pad "1" smd rect
			(at -1.82499 0 180)
			(size 1.0668 2.5146)
			(layers "F.Cu" "F.Mask" "F.Paste")
			(net "SW_P12V_AUX_PVDD11_S3_P1_FLT")
		)
		(pad "2" smd rect
			(at 1.82499 0 180)
			(size 1.0668 2.5146)
			(layers "F.Cu" "F.Mask" "F.Paste")
			(net "P12V_AUX")
		)
	)
)
